(kicad_pcb
	(version 20260206)
	(generator "pcbnew")
	(generator_version "10.0")
	(general
		(thickness 1.6)
		(legacy_teardrops no)
	)
	(paper "A4")
	(title_block
		(title "Bryce Canyon_IOM_M2_16342-2_OCP.brd")
		(comment 1 "Bryce Canyon / footprints 821-828 of 1146")
	)
	(layers
		(0 "F.Cu" signal "TOP")
		(4 "In1.Cu" signal "L2GND")
		(6 "In2.Cu" signal "L3")
		(8 "In3.Cu" signal "L4VCC")
		(10 "In4.Cu" signal "L5VCC")
		(12 "In5.Cu" signal "L6")
		(14 "In6.Cu" signal "L7GND")
		(2 "B.Cu" signal "BOTTOM")
		(9 "F.Adhes" user "F.Adhesive")
		(11 "B.Adhes" user "B.Adhesive")
		(13 "F.Paste" user "Package Geometry/Pastemask Top")
		(15 "B.Paste" user "Package Geometry/Pastemask Bottom")
		(5 "F.SilkS" user "Ref Des/Silkscreen Top")
		(7 "B.SilkS" user "Ref Des/Silkscreen Bottom")
		(1 "F.Mask" user "Board Geometry/Soldermask Top")
		(3 "B.Mask" user "Board Geometry/Soldermask Bottom")
		(17 "Dwgs.User" user "User.Drawings")
		(19 "Cmts.User" user "User.Comments")
		(21 "Eco1.User" user "User.Eco1")
		(23 "Eco2.User" user "User.Eco2")
		(25 "Edge.Cuts" user "Board Geometry/Outline")
		(27 "Margin" user)
		(31 "F.CrtYd" user "Package Geometry/Place Bound Top")
		(29 "B.CrtYd" user "Package Geometry/Place Bound Bottom")
		(35 "F.Fab" user "Ref Des/Assembly Top")
		(33 "B.Fab" user "Ref Des/Assembly Bottom")
	)
	(footprint ""
		(layer "B.Cu")
		(at 35.862006 -152.028398 180)
		(property "Reference" "C54"
			(at 0 0 0)
			(layer "B.SilkS")
			(hide yes)
			(effects
				(font
					(size 1.27 1.27)
				)
				(justify mirror)
			)
		)
		(property "Value" "SC1U16V3KX-5GP"
			(at 0 -2.8194 180)
			(unlocked yes)
			(layer "B.Fab")
			(hide yes)
			(effects
				(font
					(size 1.016 1.016)
					(thickness 0.1524)
				)
				(justify mirror)
			)
		)
		(property "Device Type" "C603H36"
			(at 0 -4.3434 180)
			(unlocked yes)
			(layer "B.Fab")
			(hide yes)
			(effects
				(font
					(size 1.016 1.016)
					(thickness 0.1524)
				)
				(justify mirror)
			)
		)
		(duplicate_pad_numbers_are_jumpers no)
		(fp_line
			(start -0.508 0)
			(end 0.508 0)
			(stroke
				(width 0.2032)
				(type default)
			)
			(layer "B.SilkS")
		)
		(fp_rect
			(start 0.5842 1.3335)
			(end -0.5842 -1.3335)
			(stroke
				(width 0)
				(type default)
			)
			(fill no)
			(layer "B.CrtYd")
		)
		(fp_rect
			(start 0.5842 1.3335)
			(end -0.5842 -1.3335)
			(stroke
				(width 0)
				(type default)
			)
			(fill no)
			(layer "B.Fab")
		)
		(pad "1" smd custom
			(at 0 -0.762)
			(size 0.2159 0.2159)
			(layers "B.Cu" "B.Mask" "B.Paste")
			(net "DDR_VREF")
			(options
				(clearance outline)
				(anchor circle)
			)
			(primitives
				(gr_poly
					(pts
						(arc
							(start -0.3302 0.4318)
							(mid -0.402042 0.402042)
							(end -0.4318 0.3302)
						)
						(arc
							(start -0.4318 -0.3302)
							(mid -0.402042 -0.402042)
							(end -0.3302 -0.4318)
						)
						(arc
							(start 0.3302 -0.4318)
							(mid 0.402042 -0.402042)
							(end 0.4318 -0.3302)
						)
						(arc
							(start 0.4318 0.3302)
							(mid 0.402042 0.402042)
							(end 0.3302 0.4318)
						)
					)
					(width 0)
					(fill yes)
				)
			)
		)
		(pad "2" smd custom
			(at 0 0.762)
			(size 0.2159 0.2159)
			(layers "B.Cu" "B.Mask" "B.Paste")
			(net "GND")
			(options
				(clearance outline)
				(anchor circle)
			)
			(primitives
				(gr_poly
					(pts
						(arc
							(start -0.3302 0.4318)
							(mid -0.402042 0.402042)
							(end -0.4318 0.3302)
						)
						(arc
							(start -0.4318 -0.3302)
							(mid -0.402042 -0.402042)
							(end -0.3302 -0.4318)
						)
						(arc
							(start 0.3302 -0.4318)
							(mid 0.402042 -0.402042)
							(end 0.4318 -0.3302)
						)
						(arc
							(start 0.4318 0.3302)
							(mid 0.402042 0.402042)
							(end 0.3302 0.4318)
						)
					)
					(width 0)
					(fill yes)
				)
			)
		)
	)
	(footprint ""
		(layer "B.Cu")
		(at 38.231064 -144.85747 -90)
		(property "Reference" "C71"
			(at 0 0 90)
			(layer "B.SilkS")
			(hide yes)
			(effects
				(font
					(size 1.27 1.27)
				)
				(justify mirror)
			)
		)
		(property "Value" "SCD1U16V2KX-3GP"
			(at -1.1811 -2.7051 270)
			(unlocked yes)
			(layer "B.Fab")
			(hide yes)
			(effects
				(font
					(size 1.016 1.016)
					(thickness 0.1524)
				)
				(justify mirror)
			)
		)
		(property "Device Type" "C402H22"
			(at -1.1811 -4.2291 270)
			(unlocked yes)
			(layer "B.Fab")
			(hide yes)
			(effects
				(font
					(size 1.016 1.016)
					(thickness 0.1524)
				)
				(justify mirror)
			)
		)
		(duplicate_pad_numbers_are_jumpers no)
		(fp_rect
			(start 0.4318 0.9525)
			(end -0.4318 -0.9525)
			(stroke
				(width 0)
				(type default)
			)
			(fill no)
			(layer "B.CrtYd")
		)
		(fp_rect
			(start 0.4318 0.9525)
			(end -0.4318 -0.9525)
			(stroke
				(width 0)
				(type default)
			)
			(fill no)
			(layer "B.Fab")
		)
		(pad "1" smd custom
			(at 0 -0.4445 90)
			(size 0.1524 0.1524)
			(layers "B.Cu" "B.Mask" "B.Paste")
			(net "GND")
			(options
				(clearance outline)
				(anchor circle)
			)
			(primitives
				(gr_poly
					(pts
						(arc
							(start 0.3048 0.2032)
							(mid 0.275042 0.275042)
							(end 0.2032 0.3048)
						)
						(arc
							(start -0.2032 0.3048)
							(mid -0.275042 0.275042)
							(end -0.3048 0.2032)
						)
						(arc
							(start -0.3048 -0.2032)
							(mid -0.275042 -0.275042)
							(end -0.2032 -0.3048)
						)
						(arc
							(start 0.2032 -0.3048)
							(mid 0.275042 -0.275042)
							(end 0.3048 -0.2032)
						)
					)
					(width 0)
					(fill yes)
				)
			)
		)
		(pad "2" smd custom
			(at 0 0.4445 90)
			(size 0.1524 0.1524)
			(layers "B.Cu" "B.Mask" "B.Paste")
			(net "P1V2_STBY")
			(options
				(clearance outline)
				(anchor circle)
			)
			(primitives
				(gr_poly
					(pts
						(arc
							(start 0.3048 0.2032)
							(mid 0.275042 0.275042)
							(end 0.2032 0.3048)
						)
						(arc
							(start -0.2032 0.3048)
							(mid -0.275042 0.275042)
							(end -0.3048 0.2032)
						)
						(arc
							(start -0.3048 -0.2032)
							(mid -0.275042 -0.275042)
							(end -0.2032 -0.3048)
						)
						(arc
							(start 0.2032 -0.3048)
							(mid 0.275042 -0.275042)
							(end 0.3048 -0.2032)
						)
					)
					(width 0)
					(fill yes)
				)
			)
		)
	)
	(footprint ""
		(layer "B.Cu")
		(at 195.197476 -137.218674 90)
		(property "Reference" "R809"
			(at 0 0 90)
			(layer "B.SilkS")
			(hide yes)
			(effects
				(font
					(size 1.27 1.27)
				)
				(justify mirror)
			)
		)
		(property "Value" "0R2J-2-GP"
			(at -0.064008 -3.993896 90)
			(unlocked yes)
			(layer "B.Fab")
			(hide yes)
			(effects
				(font
					(size 1.016 1.016)
					(thickness 0.1524)
				)
				(justify mirror)
			)
		)
		(property "Device Type" "R402H16"
			(at -0.064008 -5.517896 90)
			(unlocked yes)
			(layer "B.Fab")
			(hide yes)
			(effects
				(font
					(size 1.016 1.016)
					(thickness 0.1524)
				)
				(justify mirror)
			)
		)
		(duplicate_pad_numbers_are_jumpers no)
		(fp_line
			(start 0.508 -0.9398)
			(end 0.508 0.9398)
			(stroke
				(width 0.1524)
				(type default)
			)
			(layer "B.SilkS")
		)
		(fp_line
			(start -0.508 -0.9398)
			(end 0.508 -0.9398)
			(stroke
				(width 0.1524)
				(type default)
			)
			(layer "B.SilkS")
		)
		(fp_rect
			(start 0.508 0.9398)
			(end -0.508 -0.9398)
			(stroke
				(width 0)
				(type default)
			)
			(fill no)
			(layer "B.CrtYd")
		)
		(fp_rect
			(start 0.508 0.9398)
			(end -0.508 -0.9398)
			(stroke
				(width 0)
				(type default)
			)
			(fill no)
			(layer "B.Fab")
		)
		(pad "1" smd custom
			(at 0 -0.4445 270)
			(size 0.1397 0.1397)
			(layers "B.Cu" "B.Mask" "B.Paste")
			(net "M2_1_PRESENT_N_R")
			(options
				(clearance outline)
				(anchor circle)
			)
			(primitives
				(gr_poly
					(pts
						(arc
							(start -0.1778 0.2794)
							(mid -0.249642 0.249642)
							(end -0.2794 0.1778)
						)
						(arc
							(start -0.2794 -0.1778)
							(mid -0.249642 -0.249642)
							(end -0.1778 -0.2794)
						)
						(arc
							(start 0.1778 -0.2794)
							(mid 0.249642 -0.249642)
							(end 0.2794 -0.1778)
						)
						(arc
							(start 0.2794 0.1778)
							(mid 0.249642 0.249642)
							(end 0.1778 0.2794)
						)
					)
					(width 0)
					(fill yes)
				)
			)
		)
		(pad "2" smd custom
			(at 0 0.4445 270)
			(size 0.1397 0.1397)
			(layers "B.Cu" "B.Mask" "B.Paste")
			(net "GND")
			(options
				(clearance outline)
				(anchor circle)
			)
			(primitives
				(gr_poly
					(pts
						(arc
							(start -0.1778 0.2794)
							(mid -0.249642 0.249642)
							(end -0.2794 0.1778)
						)
						(arc
							(start -0.2794 -0.1778)
							(mid -0.249642 -0.249642)
							(end -0.1778 -0.2794)
						)
						(arc
							(start 0.1778 -0.2794)
							(mid 0.249642 -0.249642)
							(end 0.2794 -0.1778)
						)
						(arc
							(start 0.2794 0.1778)
							(mid 0.249642 0.249642)
							(end 0.1778 0.2794)
						)
					)
					(width 0)
					(fill yes)
				)
			)
		)
	)
	(footprint ""
		(layer "B.Cu")
		(at 63.373 -157.5562 180)
		(property "Reference" "C81"
			(at 0 0 0)
			(layer "B.SilkS")
			(hide yes)
			(effects
				(font
					(size 1.27 1.27)
				)
				(justify mirror)
			)
		)
		(property "Value" "SC4D7U25V5KX-1-GP"
			(at 0.0762 -6.1214 180)
			(unlocked yes)
			(layer "B.Fab")
			(hide yes)
			(effects
				(font
					(size 1.016 1.016)
					(thickness 0.1524)
				)
				(justify mirror)
			)
		)
		(property "Device Type" "C805H58"
			(at 0.0762 -8.1534 180)
			(unlocked yes)
			(layer "B.Fab")
			(hide yes)
			(effects
				(font
					(size 1.016 1.016)
					(thickness 0.1524)
				)
				(justify mirror)
			)
		)
		(duplicate_pad_numbers_are_jumpers no)
		(fp_line
			(start -0.635 0)
			(end 0.635 0)
			(stroke
				(width 0.508)
				(type default)
			)
			(layer "B.SilkS")
		)
		(fp_rect
			(start 0.9652 1.778)
			(end -0.9652 -1.778)
			(stroke
				(width 0)
				(type default)
			)
			(fill no)
			(layer "B.CrtYd")
		)
		(fp_poly
			(pts
				(xy 0.9652 -1.778) (xy -0.9652 -1.778) (xy -0.9652 1.778) (xy 0.9652 1.778)
			)
			(stroke
				(width 0)
				(type default)
			)
			(fill no)
			(layer "B.Fab")
		)
		(pad "1" smd rect
			(at 0 -0.9652)
			(size 1.397 1.143)
			(layers "B.Cu" "B.Mask" "B.Paste")
			(net "P3V3_STBY")
		)
		(pad "2" smd rect
			(at 0 0.9652)
			(size 1.397 1.143)
			(layers "B.Cu" "B.Mask" "B.Paste")
			(net "GND")
		)
	)
	(footprint ""
		(layer "B.Cu")
		(at 55.348632 -122.25909)
		(property "Reference" "R339"
			(at 0 0 0)
			(layer "B.SilkS")
			(hide yes)
			(effects
				(font
					(size 1.27 1.27)
				)
				(justify mirror)
			)
		)
		(property "Value" "4K7R2F-GP"
			(at -0.064008 -3.993896 0)
			(unlocked yes)
			(layer "B.Fab")
			(hide yes)
			(effects
				(font
					(size 1.016 1.016)
					(thickness 0.1524)
				)
				(justify mirror)
			)
		)
		(property "Device Type" "R402H16"
			(at -0.064008 -5.517896 0)
			(unlocked yes)
			(layer "B.Fab")
			(hide yes)
			(effects
				(font
					(size 1.016 1.016)
					(thickness 0.1524)
				)
				(justify mirror)
			)
		)
		(duplicate_pad_numbers_are_jumpers no)
		(fp_line
			(start -0.508 -0.9398)
			(end 0.508 -0.9398)
			(stroke
				(width 0.1524)
				(type default)
			)
			(layer "B.SilkS")
		)
		(fp_line
			(start 0.508 -0.9398)
			(end 0.508 0.9398)
			(stroke
				(width 0.1524)
				(type default)
			)
			(layer "B.SilkS")
		)
		(fp_rect
			(start 0.508 0.9398)
			(end -0.508 -0.9398)
			(stroke
				(width 0)
				(type default)
			)
			(fill no)
			(layer "B.CrtYd")
		)
		(fp_rect
			(start 0.508 0.9398)
			(end -0.508 -0.9398)
			(stroke
				(width 0)
				(type default)
			)
			(fill no)
			(layer "B.Fab")
		)
		(pad "1" smd custom
			(at 0 -0.4445 180)
			(size 0.1397 0.1397)
			(layers "B.Cu" "B.Mask" "B.Paste")
			(net "P3V3_STBY")
			(options
				(clearance outline)
				(anchor circle)
			)
			(primitives
				(gr_poly
					(pts
						(arc
							(start -0.1778 0.2794)
							(mid -0.249642 0.249642)
							(end -0.2794 0.1778)
						)
						(arc
							(start -0.2794 -0.1778)
							(mid -0.249642 -0.249642)
							(end -0.1778 -0.2794)
						)
						(arc
							(start 0.1778 -0.2794)
							(mid 0.249642 -0.249642)
							(end 0.2794 -0.1778)
						)
						(arc
							(start 0.2794 0.1778)
							(mid 0.249642 0.249642)
							(end 0.1778 0.2794)
						)
					)
					(width 0)
					(fill yes)
				)
			)
		)
		(pad "2" smd custom
			(at 0 0.4445 180)
			(size 0.1397 0.1397)
			(layers "B.Cu" "B.Mask" "B.Paste")
			(net "TEMP_3_A1")
			(options
				(clearance outline)
				(anchor circle)
			)
			(primitives
				(gr_poly
					(pts
						(arc
							(start -0.1778 0.2794)
							(mid -0.249642 0.249642)
							(end -0.2794 0.1778)
						)
						(arc
							(start -0.2794 -0.1778)
							(mid -0.249642 -0.249642)
							(end -0.1778 -0.2794)
						)
						(arc
							(start 0.1778 -0.2794)
							(mid 0.249642 -0.249642)
							(end 0.2794 -0.1778)
						)
						(arc
							(start 0.2794 0.1778)
							(mid 0.249642 0.249642)
							(end 0.1778 0.2794)
						)
					)
					(width 0)
					(fill yes)
				)
			)
		)
	)
	(footprint ""
		(layer "B.Cu")
		(at 79.018638 -57.02681 180)
		(property "Reference" "C188"
			(at 0 0 0)
			(layer "B.SilkS")
			(hide yes)
			(effects
				(font
					(size 1.27 1.27)
				)
				(justify mirror)
			)
		)
		(property "Value" "SC10U6D3V5KX-4GP"
			(at 0.0762 -6.1214 180)
			(unlocked yes)
			(layer "B.Fab")
			(hide yes)
			(effects
				(font
					(size 1.016 1.016)
					(thickness 0.1524)
				)
				(justify mirror)
			)
		)
		(property "Device Type" "C805H58"
			(at 0.0762 -8.153146 180)
			(unlocked yes)
			(layer "B.Fab")
			(hide yes)
			(effects
				(font
					(size 1.016 1.016)
					(thickness 0.1524)
				)
				(justify mirror)
			)
		)
		(duplicate_pad_numbers_are_jumpers no)
		(fp_line
			(start -0.635254 0)
			(end 0.635 0)
			(stroke
				(width 0.508)
				(type default)
			)
			(layer "B.SilkS")
		)
		(fp_rect
			(start 0.9652 1.778254)
			(end -0.9652 -1.777746)
			(stroke
				(width 0)
				(type default)
			)
			(fill no)
			(layer "B.CrtYd")
		)
		(fp_poly
			(pts
				(xy 0.9652 -1.778) (xy -0.9652 -1.778) (xy -0.9652 1.778254) (xy 0.9652 1.778254)
			)
			(stroke
				(width 0)
				(type default)
			)
			(fill no)
			(layer "B.Fab")
		)
		(pad "1" smd rect
			(at 0 -0.9652)
			(size 1.397 1.143)
			(layers "B.Cu" "B.Mask" "B.Paste")
			(net "P3V3")
		)
		(pad "2" smd rect
			(at 0 0.9652)
			(size 1.397 1.143)
			(layers "B.Cu" "B.Mask" "B.Paste")
			(net "GND")
		)
	)
	(footprint ""
		(layer "B.Cu")
		(at 56.843168 -163.069524 -90)
		(property "Reference" "R413"
			(at 0 0 90)
			(layer "B.SilkS")
			(hide yes)
			(effects
				(font
					(size 1.27 1.27)
				)
				(justify mirror)
			)
		)
		(property "Value" "2K7R2F-GP"
			(at -0.064008 -3.993896 270)
			(unlocked yes)
			(layer "B.Fab")
			(hide yes)
			(effects
				(font
					(size 1.016 1.016)
					(thickness 0.1524)
				)
				(justify mirror)
			)
		)
		(property "Device Type" "R402H16"
			(at -0.064008 -5.517896 270)
			(unlocked yes)
			(layer "B.Fab")
			(hide yes)
			(effects
				(font
					(size 1.016 1.016)
					(thickness 0.1524)
				)
				(justify mirror)
			)
		)
		(duplicate_pad_numbers_are_jumpers no)
		(fp_line
			(start -0.508 -0.9398)
			(end 0.508 -0.9398)
			(stroke
				(width 0.1524)
				(type default)
			)
			(layer "B.SilkS")
		)
		(fp_line
			(start 0.508 -0.9398)
			(end 0.508 0.9398)
			(stroke
				(width 0.1524)
				(type default)
			)
			(layer "B.SilkS")
		)
		(fp_rect
			(start 0.508 0.9398)
			(end -0.508 -0.9398)
			(stroke
				(width 0)
				(type default)
			)
			(fill no)
			(layer "B.CrtYd")
		)
		(fp_rect
			(start 0.508 0.9398)
			(end -0.508 -0.9398)
			(stroke
				(width 0)
				(type default)
			)
			(fill no)
			(layer "B.Fab")
		)
		(pad "1" smd custom
			(at 0 -0.4445 90)
			(size 0.1397 0.1397)
			(layers "B.Cu" "B.Mask" "B.Paste")
			(net "P5V_STBY")
			(options
				(clearance outline)
				(anchor circle)
			)
			(primitives
				(gr_poly
					(pts
						(arc
							(start -0.1778 0.2794)
							(mid -0.249642 0.249642)
							(end -0.2794 0.1778)
						)
						(arc
							(start -0.2794 -0.1778)
							(mid -0.249642 -0.249642)
							(end -0.1778 -0.2794)
						)
						(arc
							(start 0.1778 -0.2794)
							(mid 0.249642 -0.249642)
							(end 0.2794 -0.1778)
						)
						(arc
							(start 0.2794 0.1778)
							(mid 0.249642 0.249642)
							(end 0.1778 0.2794)
						)
					)
					(width 0)
					(fill yes)
				)
			)
		)
		(pad "2" smd custom
			(at 0 0.4445 90)
			(size 0.1397 0.1397)
			(layers "B.Cu" "B.Mask" "B.Paste")
			(net "ADC_P5V_STBY")
			(options
				(clearance outline)
				(anchor circle)
			)
			(primitives
				(gr_poly
					(pts
						(arc
							(start -0.1778 0.2794)
							(mid -0.249642 0.249642)
							(end -0.2794 0.1778)
						)
						(arc
							(start -0.2794 -0.1778)
							(mid -0.249642 -0.249642)
							(end -0.1778 -0.2794)
						)
						(arc
							(start 0.1778 -0.2794)
							(mid 0.249642 -0.249642)
							(end 0.2794 -0.1778)
						)
						(arc
							(start 0.2794 0.1778)
							(mid 0.249642 0.249642)
							(end 0.1778 0.2794)
						)
					)
					(width 0)
					(fill yes)
				)
			)
		)
	)
	(footprint ""
		(layer "B.Cu")
		(at 224.989644 -78.16723 90)
		(property "Reference" "C643"
			(at 0 0 90)
			(layer "B.SilkS")
			(hide yes)
			(effects
				(font
					(size 1.27 1.27)
				)
				(justify mirror)
			)
		)
		(property "Value" "SC10U6D3V5KX-4GP"
			(at 0.0762 -6.1214 90)
			(unlocked yes)
			(layer "B.Fab")
			(hide yes)
			(effects
				(font
					(size 1.016 1.016)
					(thickness 0.1524)
				)
				(justify mirror)
			)
		)
		(property "Device Type" "C805H58"
			(at 0.0762 -8.1534 90)
			(unlocked yes)
			(layer "B.Fab")
			(hide yes)
			(effects
				(font
					(size 1.016 1.016)
					(thickness 0.1524)
				)
				(justify mirror)
			)
		)
		(duplicate_pad_numbers_are_jumpers no)
		(fp_line
			(start -0.635 0)
			(end 0.635 0)
			(stroke
				(width 0.508)
				(type default)
			)
			(layer "B.SilkS")
		)
		(fp_rect
			(start 0.9652 1.778)
			(end -0.9652 -1.778)
			(stroke
				(width 0)
				(type default)
			)
			(fill no)
			(layer "B.CrtYd")
		)
		(fp_poly
			(pts
				(xy 0.9652 -1.778) (xy -0.9652 -1.778) (xy -0.9652 1.778) (xy 0.9652 1.778)
			)
			(stroke
				(width 0)
				(type default)
			)
			(fill no)
			(layer "B.Fab")
		)
		(pad "1" smd rect
			(at 0 -0.9652 270)
			(size 1.397 1.143)
			(layers "B.Cu" "B.Mask" "B.Paste")
			(net "P3V3_M2")
		)
		(pad "2" smd rect
			(at 0 0.9652 270)
			(size 1.397 1.143)
			(layers "B.Cu" "B.Mask" "B.Paste")
			(net "GND")
		)
	)
)
